# T6G (Grand Teton) — schematic netlist excerpt (pin names and nets, part order shuffled) for the footprints in the layout excerpt that follows; sources: Cadence DE-HDL packaged netlist, KiCad conversion of 04192023_DAF0TMB3IC0_F0TG_MB_C_brd_V02_OCP.brd

C27  Q_CAP  0.1UF 25V 10% X7R  pkg 0402  page 131 : A = P12V_OCP_SFF_R ; B = GND
R1391  Q_RES  1K 1% CHIP  pkg 0201LF  page 287 : A = JTAG_TRST_RT_CPU0_P1_N ; B = GND
PL49  Q_INDUCTOR  50NH/86A IND  pkg SMLF  page 222 : \1\ = SW_P12V_AUX_PVDDIO_P1_FLT ; \2\ = P12V_AUX
C839  Q_CAP_DIFFBUS  DIFF BUS_0.22UF 6.3V 20% X6S  pkg C0201  page 64 : \1\ = P5E_CPU0_P2_TX_C_DP<15> ; \2\ = P5E_CPU0_P2_TX_DP<15>

(kicad_pcb
	(version 20260206)
	(generator "pcbnew")
	(generator_version "10.0")
	(general
		(thickness 1.6)
		(legacy_teardrops no)
	)
	(paper "A4")
	(title_block
		(title "04192023_DAF0TMB3IC0_F0TG_MB_C_brd_V02_OCP.brd")
		(comment 1 "Grand Teton / footprints 2483-2486 of 8354")
	)
	(layers
		(0 "F.Cu" signal "TOP")
		(4 "In1.Cu" signal "GND")
		(6 "In2.Cu" signal "IN1")
		(8 "In3.Cu" signal "GND1")
		(10 "In4.Cu" signal "IN2")
		(12 "In5.Cu" signal "GND2")
		(14 "In6.Cu" signal "IN3")
		(16 "In7.Cu" signal "GND3")
		(18 "In8.Cu" signal "VCC")
		(20 "In9.Cu" signal "VCC1")
		(22 "In10.Cu" signal "GND4")
		(24 "In11.Cu" signal "IN4")
		(26 "In12.Cu" signal "GND5")
		(28 "In13.Cu" signal "IN5")
		(30 "In14.Cu" signal "GND6")
		(32 "In15.Cu" signal "IN6")
		(34 "In16.Cu" signal "GND7")
		(2 "B.Cu" signal "BOTTOM")
		(9 "F.Adhes" user "F.Adhesive")
		(11 "B.Adhes" user "B.Adhesive")
		(13 "F.Paste" user "Package Geometry/Pastemask Top")
		(15 "B.Paste" user "Package Geometry/Pastemask Bottom")
		(5 "F.SilkS" user "Ref Des/Silkscreen Top")
		(7 "B.SilkS" user "Ref Des/Silkscreen Bottom")
		(1 "F.Mask" user "Board Geometry/Soldermask Top")
		(3 "B.Mask" user "Board Geometry/Soldermask Bottom")
		(17 "Dwgs.User" user "User.Drawings")
		(19 "Cmts.User" user "User.Comments")
		(21 "Eco1.User" user "User.Eco1")
		(23 "Eco2.User" user "User.Eco2")
		(25 "Edge.Cuts" user "Board Geometry/Outline")
		(27 "Margin" user)
		(31 "F.CrtYd" user "Package Geometry/Place Bound Top")
		(29 "B.CrtYd" user "Package Geometry/Place Bound Bottom")
		(35 "F.Fab" user "Ref Des/Assembly Top")
		(33 "B.Fab" user "Ref Des/Assembly Bottom")
	)
	(footprint ""
		(layer "F.Cu")
		(at 440.40171 -13.627354 180)
		(property "Reference" "C27"
			(at 0 0 180)
			(layer "F.SilkS")
			(hide yes)
			(effects
				(font
					(size 1.27 1.27)
				)
			)
		)
		(property "Value" ""
			(at 0 0 180)
			(layer "F.Fab")
			(effects
				(font
					(size 1.27 1.27)
				)
			)
		)
		(duplicate_pad_numbers_are_jumpers no)
		(fp_line
			(start 0.7874 0.4064)
			(end -0.7874 0.4064)
			(stroke
				(width 0.1524)
				(type default)
			)
			(layer "F.SilkS")
		)
		(fp_line
			(start 0.7874 -0.4064)
			(end 0.7874 0.4064)
			(stroke
				(width 0.1524)
				(type default)
			)
			(layer "F.SilkS")
		)
		(fp_line
			(start -0.7874 0.4064)
			(end -0.7874 -0.4064)
			(stroke
				(width 0.1524)
				(type default)
			)
			(layer "F.SilkS")
		)
		(fp_line
			(start -0.7874 -0.4064)
			(end 0.7874 -0.4064)
			(stroke
				(width 0.1524)
				(type default)
			)
			(layer "F.SilkS")
		)
		(fp_line
			(start 0.67945 0.3048)
			(end 0.120396 0.3048)
			(stroke
				(width 0.1)
				(type default)
			)
			(layer "F.Fab")
		)
		(fp_line
			(start 0.67945 -0.3048)
			(end 0.67945 0.3048)
			(stroke
				(width 0.1)
				(type default)
			)
			(layer "F.Fab")
		)
		(fp_line
			(start 0.12065 -0.2794)
			(end 0.12065 -0.3048)
			(stroke
				(width 0.1)
				(type default)
			)
			(layer "F.Fab")
		)
		(fp_line
			(start 0.12065 -0.3048)
			(end 0.67945 -0.3048)
			(stroke
				(width 0.1)
				(type default)
			)
			(layer "F.Fab")
		)
		(fp_line
			(start 0.120396 0.3048)
			(end 0.120396 0.2794)
			(stroke
				(width 0.1)
				(type default)
			)
			(layer "F.Fab")
		)
		(fp_line
			(start 0.120396 0.2794)
			(end -0.12065 0.2794)
			(stroke
				(width 0.1)
				(type default)
			)
			(layer "F.Fab")
		)
		(fp_line
			(start -0.12065 0.3048)
			(end -0.67945 0.3048)
			(stroke
				(width 0.1)
				(type default)
			)
			(layer "F.Fab")
		)
		(fp_line
			(start -0.12065 0.2794)
			(end -0.12065 0.3048)
			(stroke
				(width 0.1)
				(type default)
			)
			(layer "F.Fab")
		)
		(fp_line
			(start -0.12065 -0.2794)
			(end 0.12065 -0.2794)
			(stroke
				(width 0.1)
				(type default)
			)
			(layer "F.Fab")
		)
		(fp_line
			(start -0.12065 -0.305054)
			(end -0.12065 -0.2794)
			(stroke
				(width 0.1)
				(type default)
			)
			(layer "F.Fab")
		)
		(fp_line
			(start -0.67945 0.3048)
			(end -0.67945 -0.305054)
			(stroke
				(width 0.1)
				(type default)
			)
			(layer "F.Fab")
		)
		(fp_line
			(start -0.67945 -0.305054)
			(end -0.12065 -0.305054)
			(stroke
				(width 0.1)
				(type default)
			)
			(layer "F.Fab")
		)
		(pad "1" smd circle
			(at -0.40005 0 180)
			(size 0 0)
			(layers "F.Cu" "F.Mask" "F.Paste")
			(net "P12V_OCP_SFF_R")
		)
		(pad "2" smd circle
			(at 0.40005 0 180)
			(size 0 0)
			(layers "F.Cu" "F.Mask" "F.Paste")
			(net "GND")
		)
	)
	(footprint ""
		(layer "F.Cu")
		(at 360.190542 -400.6088)
		(property "Reference" "R1391"
			(at 0 0 0)
			(layer "F.SilkS")
			(hide yes)
			(effects
				(font
					(size 1.27 1.27)
				)
			)
		)
		(property "Value" ""
			(at 0 0 0)
			(layer "F.Fab")
			(effects
				(font
					(size 1.27 1.27)
				)
			)
		)
		(duplicate_pad_numbers_are_jumpers no)
		(fp_line
			(start -0.32512 -0.175006)
			(end 0.32512 -0.175006)
			(stroke
				(width 0.1)
				(type default)
			)
			(layer "F.Fab")
		)
		(fp_line
			(start -0.32512 0.175006)
			(end -0.32512 -0.175006)
			(stroke
				(width 0.1)
				(type default)
			)
			(layer "F.Fab")
		)
		(fp_line
			(start 0.32512 -0.175006)
			(end 0.32512 0.175006)
			(stroke
				(width 0.1)
				(type default)
			)
			(layer "F.Fab")
		)
		(fp_line
			(start 0.32512 0.175006)
			(end -0.32512 0.175006)
			(stroke
				(width 0.1)
				(type default)
			)
			(layer "F.Fab")
		)
		(pad "1" smd rect
			(at -0.2667 0)
			(size 0.3048 0.381)
			(layers "F.Cu" "F.Mask" "F.Paste")
			(net "JTAG_TRST_RT_CPU0_P1_N")
		)
		(pad "2" smd rect
			(at 0.2667 0 180)
			(size 0.3048 0.381)
			(layers "F.Cu" "F.Mask" "F.Paste")
			(net "GND")
		)
	)
	(footprint ""
		(layer "F.Cu")
		(at 49.61763 -360.025696 90)
		(property "Reference" "PL49"
			(at 4.310634 -1.48463 0)
			(unlocked yes)
			(layer "F.SilkS")
			(effects
				(font
					(size 0.7874 0.5842)
					(thickness 0.1524)
				)
				(justify left)
			)
		)
		(property "Value" ""
			(at 0 0 90)
			(layer "F.Fab")
			(effects
				(font
					(size 1.27 1.27)
				)
			)
		)
		(duplicate_pad_numbers_are_jumpers no)
		(fp_line
			(start 3.050032 -2.999994)
			(end -3.050032 -2.999994)
			(stroke
				(width 0.1524)
				(type default)
			)
			(layer "F.SilkS")
		)
		(fp_line
			(start -3.050032 -2.999994)
			(end -3.050032 -1.4478)
			(stroke
				(width 0.1524)
				(type default)
			)
			(layer "F.SilkS")
		)
		(fp_line
			(start 3.050032 -1.4478)
			(end 3.050032 -2.999994)
			(stroke
				(width 0.1524)
				(type default)
			)
			(layer "F.SilkS")
		)
		(fp_line
			(start -3.050032 1.4478)
			(end -3.050032 2.999994)
			(stroke
				(width 0.1524)
				(type default)
			)
			(layer "F.SilkS")
		)
		(fp_line
			(start 3.050032 2.999994)
			(end 3.050032 1.4478)
			(stroke
				(width 0.1524)
				(type default)
			)
			(layer "F.SilkS")
		)
		(fp_line
			(start -3.050032 2.999994)
			(end 3.050032 2.999994)
			(stroke
				(width 0.1524)
				(type default)
			)
			(layer "F.SilkS")
		)
		(fp_line
			(start 3.050032 -2.999994)
			(end -3.050032 -2.999994)
			(stroke
				(width 0.1)
				(type default)
			)
			(layer "F.Fab")
		)
		(fp_line
			(start -3.050032 -2.999994)
			(end -3.050032 2.999994)
			(stroke
				(width 0.1)
				(type default)
			)
			(layer "F.Fab")
		)
		(fp_line
			(start 3.050032 2.999994)
			(end 3.050032 -2.999994)
			(stroke
				(width 0.1)
				(type default)
			)
			(layer "F.Fab")
		)
		(fp_line
			(start -3.050032 2.999994)
			(end 3.050032 2.999994)
			(stroke
				(width 0.1)
				(type default)
			)
			(layer "F.Fab")
		)
		(pad "1" smd rect
			(at -2.525014 0 90)
			(size 1.651 2.6162)
			(layers "F.Cu" "F.Mask" "F.Paste")
			(net "SW_P12V_AUX_PVDDIO_P1_FLT")
		)
		(pad "2" smd rect
			(at 2.525014 0 90)
			(size 1.651 2.6162)
			(layers "F.Cu" "F.Mask" "F.Paste")
			(net "P12V_AUX")
		)
	)
	(footprint ""
		(layer "F.Cu")
		(at 425.36872 -387.853428)
		(property "Reference" "C839"
			(at 0 0 0)
			(layer "F.SilkS")
			(hide yes)
			(effects
				(font
					(size 1.27 1.27)
				)
			)
		)
		(property "Value" ""
			(at 0 0 0)
			(layer "F.Fab")
			(effects
				(font
					(size 1.27 1.27)
				)
			)
		)
		(duplicate_pad_numbers_are_jumpers no)
		(fp_line
			(start -0.299974 -0.150114)
			(end 0.299974 -0.150114)
			(stroke
				(width 0.1)
				(type default)
			)
			(layer "F.Fab")
		)
		(fp_line
			(start -0.299974 0.150114)
			(end -0.299974 -0.150114)
			(stroke
				(width 0.1)
				(type default)
			)
			(layer "F.Fab")
		)
		(fp_line
			(start 0.299974 -0.150114)
			(end 0.299974 0.150114)
			(stroke
				(width 0.1)
				(type default)
			)
			(layer "F.Fab")
		)
		(fp_line
			(start 0.299974 0.150114)
			(end -0.299974 0.150114)
			(stroke
				(width 0.1)
				(type default)
			)
			(layer "F.Fab")
		)
		(pad "1" smd rect
			(at -0.2667 0)
			(size 0.3048 0.381)
			(layers "F.Cu" "F.Mask" "F.Paste")
			(net "P5E_CPU0_P2_TX_C_DP<15>")
		)
		(pad "2" smd rect
			(at 0.2667 0)
			(size 0.3048 0.381)
			(layers "F.Cu" "F.Mask" "F.Paste")
			(net "P5E_CPU0_P2_TX_DP<15>")
		)
	)
)
